(kicad_pcb
	(version 20260206)
	(generator "pcbnew")
	(generator_version "10.0")
	(general
		(thickness 1.6)
		(legacy_teardrops no)
	)
	(paper "A4")
	(title_block
		(title "Wiwynn_Tioga_Pass_MB.brd")
		(comment 1 "Tioga Pass / footprints 2129-2135 of 4770")
	)
	(layers
		(0 "F.Cu" signal "TOP")
		(4 "In1.Cu" signal "L2GND")
		(6 "In2.Cu" signal "L3")
		(8 "In3.Cu" signal "L4GND")
		(10 "In4.Cu" signal "L5")
		(12 "In5.Cu" signal "L6GND")
		(14 "In6.Cu" signal "L7VCC")
		(16 "In7.Cu" signal "L8VCC")
		(18 "In8.Cu" signal "L9GND")
		(20 "In9.Cu" signal "L10")
		(22 "In10.Cu" signal "L11GND")
		(24 "In11.Cu" signal "L12")
		(26 "In12.Cu" signal "L13GND")
		(2 "B.Cu" signal "BOTTOM")
		(9 "F.Adhes" user "F.Adhesive")
		(11 "B.Adhes" user "B.Adhesive")
		(13 "F.Paste" user "Package Geometry/Pastemask Top")
		(15 "B.Paste" user "Package Geometry/Pastemask Bottom")
		(5 "F.SilkS" user "Ref Des/Silkscreen Top")
		(7 "B.SilkS" user "Ref Des/Silkscreen Bottom")
		(1 "F.Mask" user "Board Geometry/Soldermask Top")
		(3 "B.Mask" user "Board Geometry/Soldermask Bottom")
		(17 "Dwgs.User" user "User.Drawings")
		(19 "Cmts.User" user "User.Comments")
		(21 "Eco1.User" user "User.Eco1")
		(23 "Eco2.User" user "User.Eco2")
		(25 "Edge.Cuts" user "Board Geometry/Outline")
		(27 "Margin" user)
		(31 "F.CrtYd" user "Package Geometry/Place Bound Top")
		(29 "B.CrtYd" user "Package Geometry/Place Bound Bottom")
		(35 "F.Fab" user "Ref Des/Assembly Top")
		(33 "B.Fab" user "Ref Des/Assembly Bottom")
	)
	(footprint ""
		(layer "F.Cu")
		(at 369.4684 -141.2494 180)
		(property "Reference" "C7A27"
			(at -0.5588 -2.76987 0)
			(unlocked yes)
			(layer "F.SilkS")
			(effects
				(font
					(size 0.7874 0.5842)
					(thickness 0.1524)
				)
			)
		)
		(property "Value" ""
			(at 0 0 180)
			(layer "F.Fab")
			(effects
				(font
					(size 1.27 1.27)
				)
			)
		)
		(duplicate_pad_numbers_are_jumpers no)
		(fp_line
			(start 2.504948 1.633728)
			(end 1.6002 1.633728)
			(stroke
				(width 0.1524)
				(type default)
			)
			(layer "F.SilkS")
		)
		(fp_line
			(start 2.504948 -1.616456)
			(end 2.504948 1.633728)
			(stroke
				(width 0.1524)
				(type default)
			)
			(layer "F.SilkS")
		)
		(fp_line
			(start 2.286 7.366)
			(end 2.286 1.63195)
			(stroke
				(width 0.1524)
				(type default)
			)
			(layer "F.SilkS")
		)
		(fp_line
			(start 2.286 7.366)
			(end 1.600708 7.366)
			(stroke
				(width 0.1524)
				(type default)
			)
			(layer "F.SilkS")
		)
		(fp_line
			(start 1.6002 -1.616456)
			(end 2.504948 -1.616456)
			(stroke
				(width 0.1524)
				(type default)
			)
			(layer "F.SilkS")
		)
		(fp_line
			(start -1.6002 -1.616456)
			(end -2.563114 -1.616456)
			(stroke
				(width 0.1524)
				(type default)
			)
			(layer "F.SilkS")
		)
		(fp_line
			(start -2.286 7.366)
			(end -1.60147 7.366)
			(stroke
				(width 0.1524)
				(type default)
			)
			(layer "F.SilkS")
		)
		(fp_line
			(start -2.286 7.366)
			(end -2.286 1.632712)
			(stroke
				(width 0.1524)
				(type default)
			)
			(layer "F.SilkS")
		)
		(fp_line
			(start -2.563114 1.633728)
			(end -1.6002 1.633728)
			(stroke
				(width 0.1524)
				(type default)
			)
			(layer "F.SilkS")
		)
		(fp_line
			(start -2.563114 -1.616456)
			(end -2.563114 1.633728)
			(stroke
				(width 0.1524)
				(type default)
			)
			(layer "F.SilkS")
		)
		(fp_rect
			(start -2.286 7.366)
			(end 2.286 -0.254)
			(stroke
				(width 0)
				(type default)
			)
			(fill no)
			(layer "F.CrtYd")
		)
		(fp_line
			(start 2.286 7.366)
			(end -2.286 7.366)
			(stroke
				(width 0.1)
				(type default)
			)
			(layer "F.Fab")
		)
		(fp_line
			(start 2.286 -0.254)
			(end 2.286 7.366)
			(stroke
				(width 0.1)
				(type default)
			)
			(layer "F.Fab")
		)
		(fp_line
			(start -2.286 7.366)
			(end -2.286 -0.254)
			(stroke
				(width 0.1)
				(type default)
			)
			(layer "F.Fab")
		)
		(fp_line
			(start -2.286 -0.254)
			(end 2.286 -0.254)
			(stroke
				(width 0.1)
				(type default)
			)
			(layer "F.Fab")
		)
		(pad "1" smd rect
			(at 0 0 180)
			(size 2.54 3.048)
			(layers "F.Cu" "F.Mask" "F.Paste")
			(net "PVNN_PCH_STBY")
		)
		(pad "2" smd rect
			(at 0 7.112 180)
			(size 2.54 3.048)
			(layers "F.Cu" "F.Mask" "F.Paste")
			(net "GND")
		)
	)
	(footprint ""
		(layer "F.Cu")
		(at -2.667 -130.1242 -90)
		(property "Reference" "R12W34"
			(at -0.8382 -0.67818 270)
			(unlocked yes)
			(layer "F.SilkS")
			(effects
				(font
					(size 0.4064 0.254)
					(thickness 0.1524)
				)
				(justify left)
			)
		)
		(property "Value" ""
			(at 0 0 270)
			(layer "F.Fab")
			(effects
				(font
					(size 1.27 1.27)
				)
			)
		)
		(duplicate_pad_numbers_are_jumpers no)
		(fp_poly
			(pts
				(xy -0.2794 -0.1016) (xy 0.2794 -0.1016) (xy 0.2794 0.9906) (xy -0.2794 0.9906)
			)
			(stroke
				(width 0)
				(type default)
			)
			(fill no)
			(layer "F.CrtYd")
		)
		(fp_line
			(start -0.2794 0.9906)
			(end 0.2794 0.9906)
			(stroke
				(width 0.1)
				(type default)
			)
			(layer "F.Fab")
		)
		(fp_line
			(start 0.2794 0.9906)
			(end 0.2794 -0.1016)
			(stroke
				(width 0.1)
				(type default)
			)
			(layer "F.Fab")
		)
		(fp_line
			(start -0.2794 -0.1016)
			(end -0.2794 0.9906)
			(stroke
				(width 0.1)
				(type default)
			)
			(layer "F.Fab")
		)
		(fp_line
			(start 0.2794 -0.1016)
			(end -0.2794 -0.1016)
			(stroke
				(width 0.1)
				(type default)
			)
			(layer "F.Fab")
		)
		(pad "1" smd rect
			(at 0 0 270)
			(size 0.508 0.508)
			(layers "F.Cu" "F.Mask" "F.Paste")
			(net "PU_VR_PVDDQ_KLM_FAULT1")
		)
		(pad "2" smd rect
			(at 0 0.889 270)
			(size 0.508 0.508)
			(layers "F.Cu" "F.Mask" "F.Paste")
			(net "PWRGD_PVDDQ_KLM")
		)
		(zone
			(layer "F.Cu")
			(hatch none 0.5)
			(connect_pads
				(clearance 0)
			)
			(min_thickness 0.25)
			(keepout
				(tracks not_allowed)
				(vias allowed)
				(pads allowed)
				(copperpour not_allowed)
				(footprints allowed)
			)
			(placement
				(enabled no)
				(sheetname "")
			)
			(fill
				(thermal_gap 0.5)
				(thermal_bridge_width 0.5)
				(island_removal_mode 0)
			)
			(polygon
				(pts
					(xy -3.302 -130.3782) (xy -3.302 -129.8702) (xy -2.921 -129.8702) (xy -2.921 -130.3782)
				)
			)
		)
		(zone
			(layer "F.Cu")
			(hatch none 0.5)
			(connect_pads
				(clearance 0)
			)
			(min_thickness 0.25)
			(keepout
				(tracks allowed)
				(vias not_allowed)
				(pads allowed)
				(copperpour not_allowed)
				(footprints allowed)
			)
			(placement
				(enabled no)
				(sheetname "")
			)
			(fill
				(thermal_gap 0.5)
				(thermal_bridge_width 0.5)
				(island_removal_mode 0)
			)
			(polygon
				(pts
					(xy -2.921 -130.3782) (xy -2.921 -129.8702) (xy -3.302 -129.8702) (xy -3.302 -130.3782)
				)
			)
		)
	)
	(footprint ""
		(layer "F.Cu")
		(at 14.986 -84.963 -90)
		(property "Reference" "R1D11"
			(at 0 0 270)
			(layer "F.SilkS")
			(hide yes)
			(effects
				(font
					(size 1.27 1.27)
				)
			)
		)
		(property "Value" ""
			(at 0 0 270)
			(layer "F.Fab")
			(effects
				(font
					(size 1.27 1.27)
				)
			)
		)
		(duplicate_pad_numbers_are_jumpers no)
		(fp_poly
			(pts
				(xy -0.2794 -0.1016) (xy 0.2794 -0.1016) (xy 0.2794 0.9906) (xy -0.2794 0.9906)
			)
			(stroke
				(width 0)
				(type default)
			)
			(fill no)
			(layer "F.CrtYd")
		)
		(fp_line
			(start -0.2794 0.9906)
			(end 0.2794 0.9906)
			(stroke
				(width 0.1)
				(type default)
			)
			(layer "F.Fab")
		)
		(fp_line
			(start 0.2794 0.9906)
			(end 0.2794 -0.1016)
			(stroke
				(width 0.1)
				(type default)
			)
			(layer "F.Fab")
		)
		(fp_line
			(start -0.2794 -0.1016)
			(end -0.2794 0.9906)
			(stroke
				(width 0.1)
				(type default)
			)
			(layer "F.Fab")
		)
		(fp_line
			(start 0.2794 -0.1016)
			(end -0.2794 -0.1016)
			(stroke
				(width 0.1)
				(type default)
			)
			(layer "F.Fab")
		)
		(pad "1" smd rect
			(at 0 0 270)
			(size 0.508 0.508)
			(layers "F.Cu" "F.Mask" "F.Paste")
			(net "A_HSC_LOW_EN")
		)
		(pad "2" smd rect
			(at 0 0.889 270)
			(size 0.508 0.508)
			(layers "F.Cu" "F.Mask" "F.Paste")
			(net "AGND_HSC")
		)
		(zone
			(layer "F.Cu")
			(hatch none 0.5)
			(connect_pads
				(clearance 0)
			)
			(min_thickness 0.25)
			(keepout
				(tracks not_allowed)
				(vias allowed)
				(pads allowed)
				(copperpour not_allowed)
				(footprints allowed)
			)
			(placement
				(enabled no)
				(sheetname "")
			)
			(fill
				(thermal_gap 0.5)
				(thermal_bridge_width 0.5)
				(island_removal_mode 0)
			)
			(polygon
				(pts
					(xy 14.351 -85.217) (xy 14.351 -84.709) (xy 14.732 -84.709) (xy 14.732 -85.217)
				)
			)
		)
		(zone
			(layer "F.Cu")
			(hatch none 0.5)
			(connect_pads
				(clearance 0)
			)
			(min_thickness 0.25)
			(keepout
				(tracks allowed)
				(vias not_allowed)
				(pads allowed)
				(copperpour not_allowed)
				(footprints allowed)
			)
			(placement
				(enabled no)
				(sheetname "")
			)
			(fill
				(thermal_gap 0.5)
				(thermal_bridge_width 0.5)
				(island_removal_mode 0)
			)
			(polygon
				(pts
					(xy 14.732 -85.217) (xy 14.732 -84.709) (xy 14.351 -84.709) (xy 14.351 -85.217)
				)
			)
		)
	)
	(footprint ""
		(layer "F.Cu")
		(at 343.408 -143.2814)
		(property "Reference" "CT47"
			(at -0.8382 -0.67818 0)
			(unlocked yes)
			(layer "F.SilkS")
			(effects
				(font
					(size 0.4064 0.254)
					(thickness 0.1524)
				)
				(justify left)
			)
		)
		(property "Value" ""
			(at 0 0 0)
			(layer "F.Fab")
			(effects
				(font
					(size 1.27 1.27)
				)
			)
		)
		(duplicate_pad_numbers_are_jumpers no)
		(fp_poly
			(pts
				(xy 0.3048 -0.1016) (xy 0.3048 0.9906) (xy -0.3048 0.9906) (xy -0.3048 -0.1016)
			)
			(stroke
				(width 0)
				(type default)
			)
			(fill no)
			(layer "F.CrtYd")
		)
		(fp_line
			(start -0.3048 -0.1016)
			(end -0.3048 0.9906)
			(stroke
				(width 0.1)
				(type default)
			)
			(layer "F.Fab")
		)
		(fp_line
			(start -0.3048 0.9906)
			(end 0.3048 0.9906)
			(stroke
				(width 0.1)
				(type default)
			)
			(layer "F.Fab")
		)
		(fp_line
			(start 0.3048 -0.1016)
			(end -0.3048 -0.1016)
			(stroke
				(width 0.1)
				(type default)
			)
			(layer "F.Fab")
		)
		(fp_line
			(start 0.3048 0.9906)
			(end 0.3048 -0.1016)
			(stroke
				(width 0.1)
				(type default)
			)
			(layer "F.Fab")
		)
		(pad "1" smd rect
			(at 0 0)
			(size 0.508 0.508)
			(layers "F.Cu" "F.Mask" "F.Paste")
			(net "VR_PVDDQ_DEF_PH2_SW")
		)
		(pad "2" smd rect
			(at 0 0.889)
			(size 0.508 0.508)
			(layers "F.Cu" "F.Mask" "F.Paste")
			(net "VR_PVDDQ_DEF_PH2_SW_RC")
		)
		(zone
			(layer "F.Cu")
			(hatch none 0.5)
			(connect_pads
				(clearance 0)
			)
			(min_thickness 0.25)
			(keepout
				(tracks allowed)
				(vias not_allowed)
				(pads allowed)
				(copperpour not_allowed)
				(footprints allowed)
			)
			(placement
				(enabled no)
				(sheetname "")
			)
			(fill
				(thermal_gap 0.5)
				(thermal_bridge_width 0.5)
				(island_removal_mode 0)
			)
			(polygon
				(pts
					(xy 343.154 -143.0274) (xy 343.662 -143.0274) (xy 343.662 -142.6464) (xy 343.154 -142.6464)
				)
			)
		)
		(zone
			(layer "F.Cu")
			(hatch none 0.5)
			(connect_pads
				(clearance 0)
			)
			(min_thickness 0.25)
			(keepout
				(tracks not_allowed)
				(vias allowed)
				(pads allowed)
				(copperpour not_allowed)
				(footprints allowed)
			)
			(placement
				(enabled no)
				(sheetname "")
			)
			(fill
				(thermal_gap 0.5)
				(thermal_bridge_width 0.5)
				(island_removal_mode 0)
			)
			(polygon
				(pts
					(xy 343.154 -142.6464) (xy 343.662 -142.6464) (xy 343.662 -143.0274) (xy 343.154 -143.0274)
				)
			)
		)
	)
	(footprint ""
		(layer "F.Cu")
		(at 338.836 -14.732 -90)
		(property "Reference" "R12W27"
			(at -0.8382 -0.67818 270)
			(unlocked yes)
			(layer "F.SilkS")
			(effects
				(font
					(size 0.4064 0.254)
					(thickness 0.1524)
				)
				(justify left)
			)
		)
		(property "Value" ""
			(at 0 0 270)
			(layer "F.Fab")
			(effects
				(font
					(size 1.27 1.27)
				)
			)
		)
		(duplicate_pad_numbers_are_jumpers no)
		(fp_poly
			(pts
				(xy -0.2794 -0.1016) (xy 0.2794 -0.1016) (xy 0.2794 0.9906) (xy -0.2794 0.9906)
			)
			(stroke
				(width 0)
				(type default)
			)
			(fill no)
			(layer "F.CrtYd")
		)
		(fp_line
			(start -0.2794 0.9906)
			(end 0.2794 0.9906)
			(stroke
				(width 0.1)
				(type default)
			)
			(layer "F.Fab")
		)
		(fp_line
			(start 0.2794 0.9906)
			(end 0.2794 -0.1016)
			(stroke
				(width 0.1)
				(type default)
			)
			(layer "F.Fab")
		)
		(fp_line
			(start -0.2794 -0.1016)
			(end -0.2794 0.9906)
			(stroke
				(width 0.1)
				(type default)
			)
			(layer "F.Fab")
		)
		(fp_line
			(start 0.2794 -0.1016)
			(end -0.2794 -0.1016)
			(stroke
				(width 0.1)
				(type default)
			)
			(layer "F.Fab")
		)
		(pad "1" smd rect
			(at 0 0 270)
			(size 0.508 0.508)
			(layers "F.Cu" "F.Mask" "F.Paste")
			(net "TP_PVDDQ_ABC_MP2")
		)
		(pad "2" smd rect
			(at 0 0.889 270)
			(size 0.508 0.508)
			(layers "F.Cu" "F.Mask" "F.Paste")
			(net "PWRGD_PVDDQ_ABC")
		)
		(zone
			(layer "F.Cu")
			(hatch none 0.5)
			(connect_pads
				(clearance 0)
			)
			(min_thickness 0.25)
			(keepout
				(tracks not_allowed)
				(vias allowed)
				(pads allowed)
				(copperpour not_allowed)
				(footprints allowed)
			)
			(placement
				(enabled no)
				(sheetname "")
			)
			(fill
				(thermal_gap 0.5)
				(thermal_bridge_width 0.5)
				(island_removal_mode 0)
			)
			(polygon
				(pts
					(xy 338.201 -14.986) (xy 338.201 -14.478) (xy 338.582 -14.478) (xy 338.582 -14.986)
				)
			)
		)
		(zone
			(layer "F.Cu")
			(hatch none 0.5)
			(connect_pads
				(clearance 0)
			)
			(min_thickness 0.25)
			(keepout
				(tracks allowed)
				(vias not_allowed)
				(pads allowed)
				(copperpour not_allowed)
				(footprints allowed)
			)
			(placement
				(enabled no)
				(sheetname "")
			)
			(fill
				(thermal_gap 0.5)
				(thermal_bridge_width 0.5)
				(island_removal_mode 0)
			)
			(polygon
				(pts
					(xy 338.582 -14.986) (xy 338.582 -14.478) (xy 338.201 -14.478) (xy 338.201 -14.986)
				)
			)
		)
	)
	(footprint ""
		(layer "F.Cu")
		(at 364.600744 -10.916158)
		(property "Reference" "C7G7"
			(at 0 0 0)
			(layer "F.SilkS")
			(hide yes)
			(effects
				(font
					(size 1.27 1.27)
				)
			)
		)
		(property "Value" ""
			(at 0 0 0)
			(layer "F.Fab")
			(effects
				(font
					(size 1.27 1.27)
				)
			)
		)
		(duplicate_pad_numbers_are_jumpers no)
		(fp_rect
			(start -0.3048 0.9906)
			(end 0.3048 -0.1016)
			(stroke
				(width 0)
				(type default)
			)
			(fill no)
			(layer "F.CrtYd")
		)
		(fp_line
			(start -0.3048 -0.1016)
			(end -0.3048 0.9906)
			(stroke
				(width 0.1)
				(type default)
			)
			(layer "F.Fab")
		)
		(fp_line
			(start -0.3048 0.9906)
			(end 0.3048 0.9906)
			(stroke
				(width 0.1)
				(type default)
			)
			(layer "F.Fab")
		)
		(fp_line
			(start 0.3048 -0.1016)
			(end -0.3048 -0.1016)
			(stroke
				(width 0.1)
				(type default)
			)
			(layer "F.Fab")
		)
		(fp_line
			(start 0.3048 0.9906)
			(end 0.3048 -0.1016)
			(stroke
				(width 0.1)
				(type default)
			)
			(layer "F.Fab")
		)
		(pad "1" smd rect
			(at 0 0)
			(size 0.508 0.508)
			(layers "F.Cu" "F.Mask" "F.Paste")
			(net "P3E_CPU0_PE2_SS_TXN<14>")
		)
		(pad "2" smd rect
			(at 0 0.889)
			(size 0.508 0.508)
			(layers "F.Cu" "F.Mask" "F.Paste")
			(net "P3E_CPU0_PE2_SS_C_TXN<14>")
		)
		(zone
			(layer "F.Cu")
			(hatch none 0.5)
			(connect_pads
				(clearance 0)
			)
			(min_thickness 0.25)
			(keepout
				(tracks allowed)
				(vias not_allowed)
				(pads allowed)
				(copperpour not_allowed)
				(footprints allowed)
			)
			(placement
				(enabled no)
				(sheetname "")
			)
			(fill
				(thermal_gap 0.5)
				(thermal_bridge_width 0.5)
				(island_removal_mode 0)
			)
			(polygon
				(pts
					(xy 364.346744 -10.281158) (xy 364.854744 -10.281158) (xy 364.854744 -10.662158) (xy 364.346744 -10.662158)
				)
			)
		)
		(zone
			(layer "F.Cu")
			(hatch none 0.5)
			(connect_pads
				(clearance 0)
			)
			(min_thickness 0.25)
			(keepout
				(tracks not_allowed)
				(vias allowed)
				(pads allowed)
				(copperpour not_allowed)
				(footprints allowed)
			)
			(placement
				(enabled no)
				(sheetname "")
			)
			(fill
				(thermal_gap 0.5)
				(thermal_bridge_width 0.5)
				(island_removal_mode 0)
			)
			(polygon
				(pts
					(xy 364.346744 -10.281158) (xy 364.854744 -10.281158) (xy 364.854744 -10.662158) (xy 364.346744 -10.662158)
				)
			)
		)
	)
	(footprint ""
		(layer "F.Cu")
		(at 324.282816 -128.025652 180)
		(property "Reference" "R6B5"
			(at 0 0 180)
			(layer "F.SilkS")
			(hide yes)
			(effects
				(font
					(size 1.27 1.27)
				)
			)
		)
		(property "Value" ""
			(at 0 0 180)
			(layer "F.Fab")
			(effects
				(font
					(size 1.27 1.27)
				)
			)
		)
		(duplicate_pad_numbers_are_jumpers no)
		(fp_poly
			(pts
				(xy -0.2794 -0.1016) (xy 0.2794 -0.1016) (xy 0.2794 0.9906) (xy -0.2794 0.9906)
			)
			(stroke
				(width 0)
				(type default)
			)
			(fill no)
			(layer "F.CrtYd")
		)
		(fp_line
			(start 0.2794 0.9906)
			(end 0.2794 -0.1016)
			(stroke
				(width 0.1)
				(type default)
			)
			(layer "F.Fab")
		)
		(fp_line
			(start 0.2794 -0.1016)
			(end -0.2794 -0.1016)
			(stroke
				(width 0.1)
				(type default)
			)
			(layer "F.Fab")
		)
		(fp_line
			(start -0.2794 0.9906)
			(end 0.2794 0.9906)
			(stroke
				(width 0.1)
				(type default)
			)
			(layer "F.Fab")
		)
		(fp_line
			(start -0.2794 -0.1016)
			(end -0.2794 0.9906)
			(stroke
				(width 0.1)
				(type default)
			)
			(layer "F.Fab")
		)
		(pad "1" smd rect
			(at 0 0 180)
			(size 0.508 0.508)
			(layers "F.Cu" "F.Mask" "F.Paste")
			(net "SVID_CLK1_CPU0")
		)
		(pad "2" smd rect
			(at 0 0.889 180)
			(size 0.508 0.508)
			(layers "F.Cu" "F.Mask" "F.Paste")
			(net "SVID_CLK1_CPU0_R")
		)
		(zone
			(layer "F.Cu")
			(hatch none 0.5)
			(connect_pads
				(clearance 0)
			)
			(min_thickness 0.25)
			(keepout
				(tracks not_allowed)
				(vias allowed)
				(pads allowed)
				(copperpour not_allowed)
				(footprints allowed)
			)
			(placement
				(enabled no)
				(sheetname "")
			)
			(fill
				(thermal_gap 0.5)
				(thermal_bridge_width 0.5)
				(island_removal_mode 0)
			)
			(polygon
				(pts
					(xy 324.536816 -128.660652) (xy 324.028816 -128.660652) (xy 324.028816 -128.279652) (xy 324.536816 -128.279652)
				)
			)
		)
		(zone
			(layer "F.Cu")
			(hatch none 0.5)
			(connect_pads
				(clearance 0)
			)
			(min_thickness 0.25)
			(keepout
				(tracks allowed)
				(vias not_allowed)
				(pads allowed)
				(copperpour not_allowed)
				(footprints allowed)
			)
			(placement
				(enabled no)
				(sheetname "")
			)
			(fill
				(thermal_gap 0.5)
				(thermal_bridge_width 0.5)
				(island_removal_mode 0)
			)
			(polygon
				(pts
					(xy 324.536816 -128.279652) (xy 324.028816 -128.279652) (xy 324.028816 -128.660652) (xy 324.536816 -128.660652)
				)
			)
		)
	)
)
